# BASEBOARD_FAB2 (Tioga Pass) — schematic netlist excerpt (pin names and nets, part order shuffled) for the footprints in the layout excerpt that follows; sources: Cadence DE-HDL packaged netlist, KiCad conversion of Wiwynn_Tioga_Pass_MB.brd

R2T27  RES  0.0 5% CHIP  pkg 0402  page 93 : A = H_CPU1_ERR1_G_N ; B = H_CPU_ERR1_GTL_R_N
R4W2  RES  1.00K 1% CHIP  pkg 0402  page 102 : A = P3V3_DB1200 ; B = P3V3_DB1200_R1
R3T5  RES  4.75K 1% CHIP  pkg 0402  page 153 : A = P3V3_STBY ; B = SPI_CS0_SECONDARY_R_N

(kicad_pcb
	(version 20260206)
	(generator "pcbnew")
	(generator_version "10.0")
	(general
		(thickness 1.6)
		(legacy_teardrops no)
	)
	(paper "A4")
	(title_block
		(title "Wiwynn_Tioga_Pass_MB.brd")
		(comment 1 "Tioga Pass / footprints 3453-3455 of 4770")
	)
	(layers
		(0 "F.Cu" signal "TOP")
		(4 "In1.Cu" signal "L2GND")
		(6 "In2.Cu" signal "L3")
		(8 "In3.Cu" signal "L4GND")
		(10 "In4.Cu" signal "L5")
		(12 "In5.Cu" signal "L6GND")
		(14 "In6.Cu" signal "L7VCC")
		(16 "In7.Cu" signal "L8VCC")
		(18 "In8.Cu" signal "L9GND")
		(20 "In9.Cu" signal "L10")
		(22 "In10.Cu" signal "L11GND")
		(24 "In11.Cu" signal "L12")
		(26 "In12.Cu" signal "L13GND")
		(2 "B.Cu" signal "BOTTOM")
		(9 "F.Adhes" user "F.Adhesive")
		(11 "B.Adhes" user "B.Adhesive")
		(13 "F.Paste" user "Package Geometry/Pastemask Top")
		(15 "B.Paste" user "Package Geometry/Pastemask Bottom")
		(5 "F.SilkS" user "Ref Des/Silkscreen Top")
		(7 "B.SilkS" user "Ref Des/Silkscreen Bottom")
		(1 "F.Mask" user "Board Geometry/Soldermask Top")
		(3 "B.Mask" user "Board Geometry/Soldermask Bottom")
		(17 "Dwgs.User" user "User.Drawings")
		(19 "Cmts.User" user "User.Comments")
		(21 "Eco1.User" user "User.Eco1")
		(23 "Eco2.User" user "User.Eco2")
		(25 "Edge.Cuts" user "Board Geometry/Outline")
		(27 "Margin" user)
		(31 "F.CrtYd" user "Package Geometry/Place Bound Top")
		(29 "B.CrtYd" user "Package Geometry/Place Bound Bottom")
		(35 "F.Fab" user "Ref Des/Assembly Top")
		(33 "B.Fab" user "Ref Des/Assembly Bottom")
	)
	(footprint ""
		(layer "B.Cu")
		(at 401.04568 -48.49368 -90)
		(property "Reference" "R3T5"
			(at 0.8382 -0.67818 270)
			(unlocked yes)
			(layer "B.SilkS")
			(effects
				(font
					(size 0.4064 0.254)
					(thickness 0.1524)
				)
				(justify left mirror)
			)
		)
		(property "Value" ""
			(at 0 0 90)
			(layer "B.Fab")
			(effects
				(font
					(size 1.27 1.27)
				)
				(justify mirror)
			)
		)
		(duplicate_pad_numbers_are_jumpers no)
		(fp_poly
			(pts
				(xy 0.2794 -0.1016) (xy -0.2794 -0.1016) (xy -0.2794 0.9906) (xy 0.2794 0.9906)
			)
			(stroke
				(width 0)
				(type default)
			)
			(fill no)
			(layer "B.CrtYd")
		)
		(fp_line
			(start -0.2794 0.9906)
			(end -0.2794 -0.1016)
			(stroke
				(width 0.1)
				(type default)
			)
			(layer "B.Fab")
		)
		(fp_line
			(start 0.2794 0.9906)
			(end -0.2794 0.9906)
			(stroke
				(width 0.1)
				(type default)
			)
			(layer "B.Fab")
		)
		(fp_line
			(start -0.2794 -0.1016)
			(end 0.2794 -0.1016)
			(stroke
				(width 0.1)
				(type default)
			)
			(layer "B.Fab")
		)
		(fp_line
			(start 0.2794 -0.1016)
			(end 0.2794 0.9906)
			(stroke
				(width 0.1)
				(type default)
			)
			(layer "B.Fab")
		)
		(pad "1" smd rect
			(at 0 0 90)
			(size 0.508 0.508)
			(layers "B.Cu" "B.Mask" "B.Paste")
			(net "P3V3_STBY")
		)
		(pad "2" smd rect
			(at 0 0.889 90)
			(size 0.508 0.508)
			(layers "B.Cu" "B.Mask" "B.Paste")
			(net "SPI_CS0_SECONDARY_R_N")
		)
		(zone
			(layer "B.Cu")
			(hatch none 0.5)
			(connect_pads
				(clearance 0)
			)
			(min_thickness 0.25)
			(keepout
				(tracks not_allowed)
				(vias allowed)
				(pads allowed)
				(copperpour not_allowed)
				(footprints allowed)
			)
			(placement
				(enabled no)
				(sheetname "")
			)
			(fill
				(thermal_gap 0.5)
				(thermal_bridge_width 0.5)
				(island_removal_mode 0)
			)
			(polygon
				(pts
					(xy 400.41068 -48.23968) (xy 400.41068 -48.74768) (xy 400.79168 -48.74768) (xy 400.79168 -48.23968)
				)
			)
		)
		(zone
			(layer "B.Cu")
			(hatch none 0.5)
			(connect_pads
				(clearance 0)
			)
			(min_thickness 0.25)
			(keepout
				(tracks allowed)
				(vias not_allowed)
				(pads allowed)
				(copperpour not_allowed)
				(footprints allowed)
			)
			(placement
				(enabled no)
				(sheetname "")
			)
			(fill
				(thermal_gap 0.5)
				(thermal_bridge_width 0.5)
				(island_removal_mode 0)
			)
			(polygon
				(pts
					(xy 400.79168 -48.23968) (xy 400.79168 -48.74768) (xy 400.41068 -48.74768) (xy 400.41068 -48.23968)
				)
			)
		)
	)
	(footprint ""
		(layer "B.Cu")
		(at 374.646952 -43.224958)
		(property "Reference" "R2T27"
			(at 0 0 0)
			(layer "B.SilkS")
			(hide yes)
			(effects
				(font
					(size 1.27 1.27)
				)
				(justify mirror)
			)
		)
		(property "Value" ""
			(at 0 0 0)
			(layer "B.Fab")
			(effects
				(font
					(size 1.27 1.27)
				)
				(justify mirror)
			)
		)
		(duplicate_pad_numbers_are_jumpers no)
		(fp_poly
			(pts
				(xy 0.2794 -0.1016) (xy -0.2794 -0.1016) (xy -0.2794 0.9906) (xy 0.2794 0.9906)
			)
			(stroke
				(width 0)
				(type default)
			)
			(fill no)
			(layer "B.CrtYd")
		)
		(fp_line
			(start -0.2794 -0.1016)
			(end 0.2794 -0.1016)
			(stroke
				(width 0.1)
				(type default)
			)
			(layer "B.Fab")
		)
		(fp_line
			(start -0.2794 0.9906)
			(end -0.2794 -0.1016)
			(stroke
				(width 0.1)
				(type default)
			)
			(layer "B.Fab")
		)
		(fp_line
			(start 0.2794 -0.1016)
			(end 0.2794 0.9906)
			(stroke
				(width 0.1)
				(type default)
			)
			(layer "B.Fab")
		)
		(fp_line
			(start 0.2794 0.9906)
			(end -0.2794 0.9906)
			(stroke
				(width 0.1)
				(type default)
			)
			(layer "B.Fab")
		)
		(pad "1" smd rect
			(at 0 0 180)
			(size 0.508 0.508)
			(layers "B.Cu" "B.Mask" "B.Paste")
			(net "H_CPU1_ERR1_G_N")
		)
		(pad "2" smd rect
			(at 0 0.889 180)
			(size 0.508 0.508)
			(layers "B.Cu" "B.Mask" "B.Paste")
			(net "H_CPU_ERR1_GTL_R_N")
		)
		(zone
			(layer "B.Cu")
			(hatch none 0.5)
			(connect_pads
				(clearance 0)
			)
			(min_thickness 0.25)
			(keepout
				(tracks allowed)
				(vias not_allowed)
				(pads allowed)
				(copperpour not_allowed)
				(footprints allowed)
			)
			(placement
				(enabled no)
				(sheetname "")
			)
			(fill
				(thermal_gap 0.5)
				(thermal_bridge_width 0.5)
				(island_removal_mode 0)
			)
			(polygon
				(pts
					(xy 374.900952 -42.970958) (xy 374.392952 -42.970958) (xy 374.392952 -42.589958) (xy 374.900952 -42.589958)
				)
			)
		)
		(zone
			(layer "B.Cu")
			(hatch none 0.5)
			(connect_pads
				(clearance 0)
			)
			(min_thickness 0.25)
			(keepout
				(tracks not_allowed)
				(vias allowed)
				(pads allowed)
				(copperpour not_allowed)
				(footprints allowed)
			)
			(placement
				(enabled no)
				(sheetname "")
			)
			(fill
				(thermal_gap 0.5)
				(thermal_bridge_width 0.5)
				(island_removal_mode 0)
			)
			(polygon
				(pts
					(xy 374.900952 -42.589958) (xy 374.392952 -42.589958) (xy 374.392952 -42.970958) (xy 374.900952 -42.970958)
				)
			)
		)
	)
	(footprint ""
		(layer "B.Cu")
		(at 174.443136 -74.018648 90)
		(property "Reference" "R4W2"
			(at 0.8382 -0.67818 90)
			(unlocked yes)
			(layer "B.SilkS")
			(effects
				(font
					(size 0.4064 0.254)
					(thickness 0.1524)
				)
				(justify left mirror)
			)
		)
		(property "Value" ""
			(at 0 0 90)
			(layer "B.Fab")
			(effects
				(font
					(size 1.27 1.27)
				)
				(justify mirror)
			)
		)
		(duplicate_pad_numbers_are_jumpers no)
		(fp_poly
			(pts
				(xy 0.2794 -0.1016) (xy -0.2794 -0.1016) (xy -0.2794 0.9906) (xy 0.2794 0.9906)
			)
			(stroke
				(width 0)
				(type default)
			)
			(fill no)
			(layer "B.CrtYd")
		)
		(fp_line
			(start 0.2794 -0.1016)
			(end 0.2794 0.9906)
			(stroke
				(width 0.1)
				(type default)
			)
			(layer "B.Fab")
		)
		(fp_line
			(start -0.2794 -0.1016)
			(end 0.2794 -0.1016)
			(stroke
				(width 0.1)
				(type default)
			)
			(layer "B.Fab")
		)
		(fp_line
			(start 0.2794 0.9906)
			(end -0.2794 0.9906)
			(stroke
				(width 0.1)
				(type default)
			)
			(layer "B.Fab")
		)
		(fp_line
			(start -0.2794 0.9906)
			(end -0.2794 -0.1016)
			(stroke
				(width 0.1)
				(type default)
			)
			(layer "B.Fab")
		)
		(pad "1" smd rect
			(at 0 0 270)
			(size 0.508 0.508)
			(layers "B.Cu" "B.Mask" "B.Paste")
			(net "P3V3_DB1200")
		)
		(pad "2" smd rect
			(at 0 0.889 270)
			(size 0.508 0.508)
			(layers "B.Cu" "B.Mask" "B.Paste")
			(net "P3V3_DB1200_R1")
		)
		(zone
			(layer "B.Cu")
			(hatch none 0.5)
			(connect_pads
				(clearance 0)
			)
			(min_thickness 0.25)
			(keepout
				(tracks allowed)
				(vias not_allowed)
				(pads allowed)
				(copperpour not_allowed)
				(footprints allowed)
			)
			(placement
				(enabled no)
				(sheetname "")
			)
			(fill
				(thermal_gap 0.5)
				(thermal_bridge_width 0.5)
				(island_removal_mode 0)
			)
			(polygon
				(pts
					(xy 174.697136 -74.272648) (xy 174.697136 -73.764648) (xy 175.078136 -73.764648) (xy 175.078136 -74.272648)
				)
			)
		)
		(zone
			(layer "B.Cu")
			(hatch none 0.5)
			(connect_pads
				(clearance 0)
			)
			(min_thickness 0.25)
			(keepout
				(tracks not_allowed)
				(vias allowed)
				(pads allowed)
				(copperpour not_allowed)
				(footprints allowed)
			)
			(placement
				(enabled no)
				(sheetname "")
			)
			(fill
				(thermal_gap 0.5)
				(thermal_bridge_width 0.5)
				(island_removal_mode 0)
			)
			(polygon
				(pts
					(xy 175.078136 -74.272648) (xy 175.078136 -73.764648) (xy 174.697136 -73.764648) (xy 174.697136 -74.272648)
				)
			)
		)
	)
)
